# S9S_MB_2U (Grand Teton) — schematic netlist excerpt (pin names and nets, part order shuffled) for the footprints in the layout excerpt that follows; sources: Cadence DE-HDL packaged netlist, KiCad conversion of 03242023_DA0F0TMBIJ0_F0T_Motherboard_J_brd_V01_OCP.brd

C2450  Q_CAP  1000PF 50V 5% EMPTY  pkg 0402  page 292 : A = PWRGD_PVCCINFAON_CPU1_R ; B = GND
R4460  Q_RES  0 5% CHIP  pkg 0402LF  page 196 : A = USB2_HOST_PCH_0_DP ; B = USB2_HUB_2_BUF_EXT_R_DP

(kicad_pcb
	(version 20260206)
	(generator "pcbnew")
	(generator_version "10.0")
	(general
		(thickness 1.6)
		(legacy_teardrops no)
	)
	(paper "A4")
	(title_block
		(title "03242023_DA0F0TMBIJ0_F0T_Motherboard_J_brd_V01_OCP.brd")
		(comment 1 "Grand Teton / footprints 3946-3947 of 6105")
	)
	(layers
		(0 "F.Cu" signal "TOP")
		(4 "In1.Cu" signal "GND")
		(6 "In2.Cu" signal "IN1")
		(8 "In3.Cu" signal "GND1")
		(10 "In4.Cu" signal "IN2")
		(12 "In5.Cu" signal "GND2")
		(14 "In6.Cu" signal "IN3")
		(16 "In7.Cu" signal "GND3")
		(18 "In8.Cu" signal "VCC")
		(20 "In9.Cu" signal "VCC1")
		(22 "In10.Cu" signal "GND4")
		(24 "In11.Cu" signal "IN4")
		(26 "In12.Cu" signal "GND5")
		(28 "In13.Cu" signal "IN5")
		(30 "In14.Cu" signal "GND6")
		(32 "In15.Cu" signal "IN6")
		(34 "In16.Cu" signal "GND7")
		(2 "B.Cu" signal "BOTTOM")
		(9 "F.Adhes" user "F.Adhesive")
		(11 "B.Adhes" user "B.Adhesive")
		(13 "F.Paste" user "Package Geometry/Pastemask Top")
		(15 "B.Paste" user "Package Geometry/Pastemask Bottom")
		(5 "F.SilkS" user "Ref Des/Silkscreen Top")
		(7 "B.SilkS" user "Ref Des/Silkscreen Bottom")
		(1 "F.Mask" user "Board Geometry/Soldermask Top")
		(3 "B.Mask" user "Board Geometry/Soldermask Bottom")
		(17 "Dwgs.User" user "User.Drawings")
		(19 "Cmts.User" user "User.Comments")
		(21 "Eco1.User" user "User.Eco1")
		(23 "Eco2.User" user "User.Eco2")
		(25 "Edge.Cuts" user "Board Geometry/Outline")
		(27 "Margin" user)
		(31 "F.CrtYd" user "Package Geometry/Place Bound Top")
		(29 "B.CrtYd" user "Package Geometry/Place Bound Bottom")
		(35 "F.Fab" user "Ref Des/Assembly Top")
		(33 "B.Fab" user "Ref Des/Assembly Bottom")
	)
	(footprint ""
		(layer "F.Cu")
		(at 155.63596 -45.452538 -90)
		(property "Reference" "R4460"
			(at 0 0 270)
			(layer "F.SilkS")
			(hide yes)
			(effects
				(font
					(size 1.27 1.27)
				)
			)
		)
		(property "Value" ""
			(at 0 0 270)
			(layer "F.Fab")
			(effects
				(font
					(size 1.27 1.27)
				)
			)
		)
		(duplicate_pad_numbers_are_jumpers no)
		(fp_line
			(start 0.7874 0.4064)
			(end -0.7874 0.4064)
			(stroke
				(width 0.1524)
				(type default)
			)
			(layer "F.SilkS")
		)
		(fp_line
			(start 0.7874 -0.4064)
			(end 0.7874 0.4064)
			(stroke
				(width 0.1524)
				(type default)
			)
			(layer "F.SilkS")
		)
		(fp_line
			(start -0.67945 0.3048)
			(end -0.67945 -0.305054)
			(stroke
				(width 0.1)
				(type default)
			)
			(layer "F.Fab")
		)
		(fp_line
			(start -0.12065 0.3048)
			(end -0.67945 0.3048)
			(stroke
				(width 0.1)
				(type default)
			)
			(layer "F.Fab")
		)
		(fp_line
			(start 0.120396 0.3048)
			(end 0.120396 0.2794)
			(stroke
				(width 0.1)
				(type default)
			)
			(layer "F.Fab")
		)
		(fp_line
			(start 0.67945 0.3048)
			(end 0.120396 0.3048)
			(stroke
				(width 0.1)
				(type default)
			)
			(layer "F.Fab")
		)
		(fp_line
			(start -0.12065 0.2794)
			(end -0.12065 0.3048)
			(stroke
				(width 0.1)
				(type default)
			)
			(layer "F.Fab")
		)
		(fp_line
			(start 0.120396 0.2794)
			(end -0.12065 0.2794)
			(stroke
				(width 0.1)
				(type default)
			)
			(layer "F.Fab")
		)
		(fp_line
			(start -0.12065 -0.2794)
			(end 0.12065 -0.2794)
			(stroke
				(width 0.1)
				(type default)
			)
			(layer "F.Fab")
		)
		(fp_line
			(start 0.12065 -0.2794)
			(end 0.12065 -0.3048)
			(stroke
				(width 0.1)
				(type default)
			)
			(layer "F.Fab")
		)
		(fp_line
			(start 0.12065 -0.3048)
			(end 0.67945 -0.3048)
			(stroke
				(width 0.1)
				(type default)
			)
			(layer "F.Fab")
		)
		(fp_line
			(start 0.67945 -0.3048)
			(end 0.67945 0.3048)
			(stroke
				(width 0.1)
				(type default)
			)
			(layer "F.Fab")
		)
		(fp_line
			(start -0.67945 -0.305054)
			(end -0.12065 -0.305054)
			(stroke
				(width 0.1)
				(type default)
			)
			(layer "F.Fab")
		)
		(fp_line
			(start -0.12065 -0.305054)
			(end -0.12065 -0.2794)
			(stroke
				(width 0.1)
				(type default)
			)
			(layer "F.Fab")
		)
		(pad "1" smd rect
			(at -0.40005 0 90)
			(size 0.4572 0.508)
			(layers "F.Cu" "F.Mask" "F.Paste")
			(net "USB2_HOST_PCH_0_DP")
		)
		(pad "2" smd rect
			(at 0.40005 0 90)
			(size 0.4572 0.508)
			(layers "F.Cu" "F.Mask" "F.Paste")
			(net "USB2_HUB_2_BUF_EXT_R_DP")
		)
	)
	(footprint ""
		(layer "F.Cu")
		(at 36.956238 -126.69774)
		(property "Reference" "C2450"
			(at 0 0 0)
			(layer "F.SilkS")
			(hide yes)
			(effects
				(font
					(size 1.27 1.27)
				)
			)
		)
		(property "Value" ""
			(at 0 0 0)
			(layer "F.Fab")
			(effects
				(font
					(size 1.27 1.27)
				)
			)
		)
		(duplicate_pad_numbers_are_jumpers no)
		(fp_line
			(start -0.7874 -0.4064)
			(end 0.7874 -0.4064)
			(stroke
				(width 0.1524)
				(type default)
			)
			(layer "F.SilkS")
		)
		(fp_line
			(start -0.7874 0.4064)
			(end -0.7874 -0.4064)
			(stroke
				(width 0.1524)
				(type default)
			)
			(layer "F.SilkS")
		)
		(fp_line
			(start 0.7874 -0.4064)
			(end 0.7874 0.4064)
			(stroke
				(width 0.1524)
				(type default)
			)
			(layer "F.SilkS")
		)
		(fp_line
			(start 0.7874 0.4064)
			(end -0.7874 0.4064)
			(stroke
				(width 0.1524)
				(type default)
			)
			(layer "F.SilkS")
		)
		(fp_line
			(start -0.67945 -0.305054)
			(end -0.12065 -0.305054)
			(stroke
				(width 0.1)
				(type default)
			)
			(layer "F.Fab")
		)
		(fp_line
			(start -0.67945 0.3048)
			(end -0.67945 -0.305054)
			(stroke
				(width 0.1)
				(type default)
			)
			(layer "F.Fab")
		)
		(fp_line
			(start -0.12065 -0.305054)
			(end -0.12065 -0.2794)
			(stroke
				(width 0.1)
				(type default)
			)
			(layer "F.Fab")
		)
		(fp_line
			(start -0.12065 -0.2794)
			(end 0.12065 -0.2794)
			(stroke
				(width 0.1)
				(type default)
			)
			(layer "F.Fab")
		)
		(fp_line
			(start -0.12065 0.2794)
			(end -0.12065 0.3048)
			(stroke
				(width 0.1)
				(type default)
			)
			(layer "F.Fab")
		)
		(fp_line
			(start -0.12065 0.3048)
			(end -0.67945 0.3048)
			(stroke
				(width 0.1)
				(type default)
			)
			(layer "F.Fab")
		)
		(fp_line
			(start 0.120396 0.2794)
			(end -0.12065 0.2794)
			(stroke
				(width 0.1)
				(type default)
			)
			(layer "F.Fab")
		)
		(fp_line
			(start 0.120396 0.3048)
			(end 0.120396 0.2794)
			(stroke
				(width 0.1)
				(type default)
			)
			(layer "F.Fab")
		)
		(fp_line
			(start 0.12065 -0.3048)
			(end 0.67945 -0.3048)
			(stroke
				(width 0.1)
				(type default)
			)
			(layer "F.Fab")
		)
		(fp_line
			(start 0.12065 -0.2794)
			(end 0.12065 -0.3048)
			(stroke
				(width 0.1)
				(type default)
			)
			(layer "F.Fab")
		)
		(fp_line
			(start 0.67945 -0.3048)
			(end 0.67945 0.3048)
			(stroke
				(width 0.1)
				(type default)
			)
			(layer "F.Fab")
		)
		(fp_line
			(start 0.67945 0.3048)
			(end 0.120396 0.3048)
			(stroke
				(width 0.1)
				(type default)
			)
			(layer "F.Fab")
		)
		(pad "1" smd circle
			(at -0.40005 0)
			(size 0 0)
			(layers "F.Cu" "F.Mask" "F.Paste")
			(net "PWRGD_PVCCINFAON_CPU1_R")
		)
		(pad "2" smd circle
			(at 0.40005 0)
			(size 0 0)
			(layers "F.Cu" "F.Mask" "F.Paste")
			(net "GND")
		)
	)
)
